(kicad_pcb
	(version 20260206)
	(generator "pcbnew")
	(generator_version "10.0")
	(general
		(thickness 1.6)
		(legacy_teardrops no)
	)
	(paper "A4")
	(title_block
		(title "Wiwynn_Tioga_Pass_MB.brd")
		(comment 1 "Tioga Pass / footprints 2847-2852 of 4770")
	)
	(layers
		(0 "F.Cu" signal "TOP")
		(4 "In1.Cu" signal "L2GND")
		(6 "In2.Cu" signal "L3")
		(8 "In3.Cu" signal "L4GND")
		(10 "In4.Cu" signal "L5")
		(12 "In5.Cu" signal "L6GND")
		(14 "In6.Cu" signal "L7VCC")
		(16 "In7.Cu" signal "L8VCC")
		(18 "In8.Cu" signal "L9GND")
		(20 "In9.Cu" signal "L10")
		(22 "In10.Cu" signal "L11GND")
		(24 "In11.Cu" signal "L12")
		(26 "In12.Cu" signal "L13GND")
		(2 "B.Cu" signal "BOTTOM")
		(9 "F.Adhes" user "F.Adhesive")
		(11 "B.Adhes" user "B.Adhesive")
		(13 "F.Paste" user "Package Geometry/Pastemask Top")
		(15 "B.Paste" user "Package Geometry/Pastemask Bottom")
		(5 "F.SilkS" user "Ref Des/Silkscreen Top")
		(7 "B.SilkS" user "Ref Des/Silkscreen Bottom")
		(1 "F.Mask" user "Board Geometry/Soldermask Top")
		(3 "B.Mask" user "Board Geometry/Soldermask Bottom")
		(17 "Dwgs.User" user "User.Drawings")
		(19 "Cmts.User" user "User.Comments")
		(21 "Eco1.User" user "User.Eco1")
		(23 "Eco2.User" user "User.Eco2")
		(25 "Edge.Cuts" user "Board Geometry/Outline")
		(27 "Margin" user)
		(31 "F.CrtYd" user "Package Geometry/Place Bound Top")
		(29 "B.CrtYd" user "Package Geometry/Place Bound Bottom")
		(35 "F.Fab" user "Ref Des/Assembly Top")
		(33 "B.Fab" user "Ref Des/Assembly Bottom")
	)
	(footprint ""
		(layer "B.Cu")
		(at 482.2825 -47.625 90)
		(property "Reference" "C1R15"
			(at 0 0 90)
			(layer "B.SilkS")
			(hide yes)
			(effects
				(font
					(size 1.27 1.27)
				)
				(justify mirror)
			)
		)
		(property "Value" ""
			(at 0 0 90)
			(layer "B.Fab")
			(effects
				(font
					(size 1.27 1.27)
				)
				(justify mirror)
			)
		)
		(duplicate_pad_numbers_are_jumpers no)
		(fp_poly
			(pts
				(xy -0.3048 -0.1016) (xy -0.3048 0.9906) (xy 0.3048 0.9906) (xy 0.3048 -0.1016)
			)
			(stroke
				(width 0)
				(type default)
			)
			(fill no)
			(layer "B.CrtYd")
		)
		(fp_line
			(start 0.3048 -0.1016)
			(end 0.3048 0.9906)
			(stroke
				(width 0.1)
				(type default)
			)
			(layer "B.Fab")
		)
		(fp_line
			(start -0.3048 -0.1016)
			(end 0.3048 -0.1016)
			(stroke
				(width 0.1)
				(type default)
			)
			(layer "B.Fab")
		)
		(fp_line
			(start 0.3048 0.9906)
			(end -0.3048 0.9906)
			(stroke
				(width 0.1)
				(type default)
			)
			(layer "B.Fab")
		)
		(fp_line
			(start -0.3048 0.9906)
			(end -0.3048 -0.1016)
			(stroke
				(width 0.1)
				(type default)
			)
			(layer "B.Fab")
		)
		(pad "1" smd rect
			(at 0 0 270)
			(size 0.508 0.508)
			(layers "B.Cu" "B.Mask" "B.Paste")
			(net "P0V9_LAN")
		)
		(pad "2" smd rect
			(at 0 0.889 270)
			(size 0.508 0.508)
			(layers "B.Cu" "B.Mask" "B.Paste")
			(net "GND")
		)
		(zone
			(layer "B.Cu")
			(hatch none 0.5)
			(connect_pads
				(clearance 0)
			)
			(min_thickness 0.25)
			(keepout
				(tracks allowed)
				(vias not_allowed)
				(pads allowed)
				(copperpour not_allowed)
				(footprints allowed)
			)
			(placement
				(enabled no)
				(sheetname "")
			)
			(fill
				(thermal_gap 0.5)
				(thermal_bridge_width 0.5)
				(island_removal_mode 0)
			)
			(polygon
				(pts
					(xy 482.5365 -47.879) (xy 482.5365 -47.371) (xy 482.9175 -47.371) (xy 482.9175 -47.879)
				)
			)
		)
		(zone
			(layer "B.Cu")
			(hatch none 0.5)
			(connect_pads
				(clearance 0)
			)
			(min_thickness 0.25)
			(keepout
				(tracks not_allowed)
				(vias allowed)
				(pads allowed)
				(copperpour not_allowed)
				(footprints allowed)
			)
			(placement
				(enabled no)
				(sheetname "")
			)
			(fill
				(thermal_gap 0.5)
				(thermal_bridge_width 0.5)
				(island_removal_mode 0)
			)
			(polygon
				(pts
					(xy 482.9175 -47.879) (xy 482.9175 -47.371) (xy 482.5365 -47.371) (xy 482.5365 -47.879)
				)
			)
		)
	)
	(footprint ""
		(layer "B.Cu")
		(at 464.625944 -7.48792 180)
		(property "Reference" "C2U22"
			(at 0 0 0)
			(layer "B.SilkS")
			(hide yes)
			(effects
				(font
					(size 1.27 1.27)
				)
				(justify mirror)
			)
		)
		(property "Value" ""
			(at 0 0 0)
			(layer "B.Fab")
			(effects
				(font
					(size 1.27 1.27)
				)
				(justify mirror)
			)
		)
		(duplicate_pad_numbers_are_jumpers no)
		(fp_poly
			(pts
				(xy -0.3048 -0.1016) (xy -0.3048 0.9906) (xy 0.3048 0.9906) (xy 0.3048 -0.1016)
			)
			(stroke
				(width 0)
				(type default)
			)
			(fill no)
			(layer "B.CrtYd")
		)
		(fp_line
			(start 0.3048 0.9906)
			(end -0.3048 0.9906)
			(stroke
				(width 0.1)
				(type default)
			)
			(layer "B.Fab")
		)
		(fp_line
			(start 0.3048 -0.1016)
			(end 0.3048 0.9906)
			(stroke
				(width 0.1)
				(type default)
			)
			(layer "B.Fab")
		)
		(fp_line
			(start -0.3048 0.9906)
			(end -0.3048 -0.1016)
			(stroke
				(width 0.1)
				(type default)
			)
			(layer "B.Fab")
		)
		(fp_line
			(start -0.3048 -0.1016)
			(end 0.3048 -0.1016)
			(stroke
				(width 0.1)
				(type default)
			)
			(layer "B.Fab")
		)
		(pad "1" smd rect
			(at 0 0)
			(size 0.508 0.508)
			(layers "B.Cu" "B.Mask" "B.Paste")
			(net "P3V3_STBY")
		)
		(pad "2" smd rect
			(at 0 0.889)
			(size 0.508 0.508)
			(layers "B.Cu" "B.Mask" "B.Paste")
			(net "GND")
		)
		(zone
			(layer "B.Cu")
			(hatch none 0.5)
			(connect_pads
				(clearance 0)
			)
			(min_thickness 0.25)
			(keepout
				(tracks not_allowed)
				(vias allowed)
				(pads allowed)
				(copperpour not_allowed)
				(footprints allowed)
			)
			(placement
				(enabled no)
				(sheetname "")
			)
			(fill
				(thermal_gap 0.5)
				(thermal_bridge_width 0.5)
				(island_removal_mode 0)
			)
			(polygon
				(pts
					(xy 464.371944 -8.12292) (xy 464.879944 -8.12292) (xy 464.879944 -7.74192) (xy 464.371944 -7.74192)
				)
			)
		)
		(zone
			(layer "B.Cu")
			(hatch none 0.5)
			(connect_pads
				(clearance 0)
			)
			(min_thickness 0.25)
			(keepout
				(tracks allowed)
				(vias not_allowed)
				(pads allowed)
				(copperpour not_allowed)
				(footprints allowed)
			)
			(placement
				(enabled no)
				(sheetname "")
			)
			(fill
				(thermal_gap 0.5)
				(thermal_bridge_width 0.5)
				(island_removal_mode 0)
			)
			(polygon
				(pts
					(xy 464.371944 -7.74192) (xy 464.879944 -7.74192) (xy 464.879944 -8.12292) (xy 464.371944 -8.12292)
				)
			)
		)
	)
	(footprint ""
		(layer "B.Cu")
		(at 385.33705 -108.65485 90)
		(property "Reference" "C3N15"
			(at 0 0 90)
			(layer "B.SilkS")
			(hide yes)
			(effects
				(font
					(size 1.27 1.27)
				)
				(justify mirror)
			)
		)
		(property "Value" ""
			(at 0 0 90)
			(layer "B.Fab")
			(effects
				(font
					(size 1.27 1.27)
				)
				(justify mirror)
			)
		)
		(duplicate_pad_numbers_are_jumpers no)
		(fp_rect
			(start 0.2794 0.9144)
			(end -0.2794 -0.1143)
			(stroke
				(width 0)
				(type default)
			)
			(fill no)
			(layer "B.CrtYd")
		)
		(fp_line
			(start 0.2794 -0.1143)
			(end -0.2794 -0.1143)
			(stroke
				(width 0.1)
				(type default)
			)
			(layer "B.Fab")
		)
		(fp_line
			(start -0.2794 -0.1143)
			(end -0.2794 0.9144)
			(stroke
				(width 0.1)
				(type default)
			)
			(layer "B.Fab")
		)
		(fp_line
			(start 0.2794 0.9144)
			(end 0.2794 -0.1143)
			(stroke
				(width 0.1)
				(type default)
			)
			(layer "B.Fab")
		)
		(fp_line
			(start -0.2794 0.9144)
			(end 0.2794 0.9144)
			(stroke
				(width 0.1)
				(type default)
			)
			(layer "B.Fab")
		)
		(pad "1" smd custom
			(at 0 0)
			(size 0.10414 0.10414)
			(layers "B.Cu" "B.Mask" "B.Paste")
			(net "PVNN_PCH_STBY")
			(options
				(clearance outline)
				(anchor circle)
			)
			(primitives
				(gr_poly
					(pts
						(xy -0.20828 -0.08636) (xy -0.20828 0.08636) (xy -0.08636 0.20828) (xy 0.086614 0.20828) (xy 0.20828 0.086614)
						(xy 0.20828 -0.08636) (xy 0.08636 -0.20828) (xy -0.08636 -0.20828)
					)
					(width 0)
					(fill yes)
				)
			)
		)
		(pad "2" smd custom
			(at 0 0.8001)
			(size 0.10414 0.10414)
			(layers "B.Cu" "B.Mask" "B.Paste")
			(net "GND")
			(options
				(clearance outline)
				(anchor circle)
			)
			(primitives
				(gr_poly
					(pts
						(xy -0.20828 -0.08636) (xy -0.20828 0.08636) (xy -0.08636 0.20828) (xy 0.086614 0.20828) (xy 0.20828 0.086614)
						(xy 0.20828 -0.08636) (xy 0.08636 -0.20828) (xy -0.08636 -0.20828)
					)
					(width 0)
					(fill yes)
				)
			)
		)
		(zone
			(layer "B.Cu")
			(hatch none 0.5)
			(connect_pads
				(clearance 0)
			)
			(min_thickness 0.25)
			(keepout
				(tracks allowed)
				(vias not_allowed)
				(pads allowed)
				(copperpour not_allowed)
				(footprints allowed)
			)
			(placement
				(enabled no)
				(sheetname "")
			)
			(fill
				(thermal_gap 0.5)
				(thermal_bridge_width 0.5)
				(island_removal_mode 0)
			)
			(polygon
				(pts
					(xy 385.5466 -108.74248) (xy 385.9276 -108.74248) (xy 385.9276 -108.56722) (xy 385.5466 -108.566966)
				)
			)
		)
		(zone
			(layer "B.Cu")
			(hatch none 0.5)
			(connect_pads
				(clearance 0)
			)
			(min_thickness 0.25)
			(keepout
				(tracks not_allowed)
				(vias allowed)
				(pads allowed)
				(copperpour not_allowed)
				(footprints allowed)
			)
			(placement
				(enabled no)
				(sheetname "")
			)
			(fill
				(thermal_gap 0.5)
				(thermal_bridge_width 0.5)
				(island_removal_mode 0)
			)
			(polygon
				(pts
					(xy 385.5466 -108.74248) (xy 385.9276 -108.74248) (xy 385.9276 -108.56722) (xy 385.5466 -108.566966)
				)
			)
		)
	)
	(footprint ""
		(layer "B.Cu")
		(at 370.9924 -131.4704 180)
		(property "Reference" "C3M31"
			(at 0 0 0)
			(layer "B.SilkS")
			(hide yes)
			(effects
				(font
					(size 1.27 1.27)
				)
				(justify mirror)
			)
		)
		(property "Value" ""
			(at 0 0 0)
			(layer "B.Fab")
			(effects
				(font
					(size 1.27 1.27)
				)
				(justify mirror)
			)
		)
		(duplicate_pad_numbers_are_jumpers no)
		(fp_rect
			(start 0.3048 -0.1016)
			(end -0.3048 0.9906)
			(stroke
				(width 0)
				(type default)
			)
			(fill no)
			(layer "B.CrtYd")
		)
		(fp_line
			(start 0.3048 0.9906)
			(end -0.3048 0.9906)
			(stroke
				(width 0.1)
				(type default)
			)
			(layer "B.Fab")
		)
		(fp_line
			(start 0.3048 -0.1016)
			(end 0.3048 0.9906)
			(stroke
				(width 0.1)
				(type default)
			)
			(layer "B.Fab")
		)
		(fp_line
			(start -0.3048 0.9906)
			(end -0.3048 -0.1016)
			(stroke
				(width 0.1)
				(type default)
			)
			(layer "B.Fab")
		)
		(fp_line
			(start -0.3048 -0.1016)
			(end 0.3048 -0.1016)
			(stroke
				(width 0.1)
				(type default)
			)
			(layer "B.Fab")
		)
		(pad "1" smd rect
			(at 0 0)
			(size 0.508 0.508)
			(layers "B.Cu" "B.Mask" "B.Paste")
			(net "P1V05_PCH_STBY")
		)
		(pad "2" smd rect
			(at 0 0.889)
			(size 0.508 0.508)
			(layers "B.Cu" "B.Mask" "B.Paste")
			(net "GND")
		)
		(zone
			(layer "B.Cu")
			(hatch none 0.5)
			(connect_pads
				(clearance 0)
			)
			(min_thickness 0.25)
			(keepout
				(tracks not_allowed)
				(vias allowed)
				(pads allowed)
				(copperpour not_allowed)
				(footprints allowed)
			)
			(placement
				(enabled no)
				(sheetname "")
			)
			(fill
				(thermal_gap 0.5)
				(thermal_bridge_width 0.5)
				(island_removal_mode 0)
			)
			(polygon
				(pts
					(xy 370.7384 -131.7244) (xy 371.2464 -131.7244) (xy 371.2464 -132.1054) (xy 370.7384 -132.1054)
				)
			)
		)
		(zone
			(layer "B.Cu")
			(hatch none 0.5)
			(connect_pads
				(clearance 0)
			)
			(min_thickness 0.25)
			(keepout
				(tracks allowed)
				(vias not_allowed)
				(pads allowed)
				(copperpour not_allowed)
				(footprints allowed)
			)
			(placement
				(enabled no)
				(sheetname "")
			)
			(fill
				(thermal_gap 0.5)
				(thermal_bridge_width 0.5)
				(island_removal_mode 0)
			)
			(polygon
				(pts
					(xy 370.7384 -131.7244) (xy 371.2464 -131.7244) (xy 371.2464 -132.1054) (xy 370.7384 -132.1054)
				)
			)
		)
	)
	(footprint ""
		(layer "B.Cu")
		(at 439.478928 -157.152848 -90)
		(property "Reference" "C25W99"
			(at 0.8382 -0.67818 270)
			(unlocked yes)
			(layer "B.SilkS")
			(effects
				(font
					(size 0.4064 0.254)
					(thickness 0.1524)
				)
				(justify left mirror)
			)
		)
		(property "Value" ""
			(at 0 0 90)
			(layer "B.Fab")
			(effects
				(font
					(size 1.27 1.27)
				)
				(justify mirror)
			)
		)
		(duplicate_pad_numbers_are_jumpers no)
		(fp_poly
			(pts
				(xy -0.3048 -0.1016) (xy -0.3048 0.9906) (xy 0.3048 0.9906) (xy 0.3048 -0.1016)
			)
			(stroke
				(width 0)
				(type default)
			)
			(fill no)
			(layer "B.CrtYd")
		)
		(fp_line
			(start -0.3048 0.9906)
			(end -0.3048 -0.1016)
			(stroke
				(width 0.1)
				(type default)
			)
			(layer "B.Fab")
		)
		(fp_line
			(start 0.3048 0.9906)
			(end -0.3048 0.9906)
			(stroke
				(width 0.1)
				(type default)
			)
			(layer "B.Fab")
		)
		(fp_line
			(start -0.3048 -0.1016)
			(end 0.3048 -0.1016)
			(stroke
				(width 0.1)
				(type default)
			)
			(layer "B.Fab")
		)
		(fp_line
			(start 0.3048 -0.1016)
			(end 0.3048 0.9906)
			(stroke
				(width 0.1)
				(type default)
			)
			(layer "B.Fab")
		)
		(pad "1" smd rect
			(at 0 0 90)
			(size 0.508 0.508)
			(layers "B.Cu" "B.Mask" "B.Paste")
			(net "P3V3_STBY")
		)
		(pad "2" smd rect
			(at 0 0.889 90)
			(size 0.508 0.508)
			(layers "B.Cu" "B.Mask" "B.Paste")
			(net "GND")
		)
		(zone
			(layer "B.Cu")
			(hatch none 0.5)
			(connect_pads
				(clearance 0)
			)
			(min_thickness 0.25)
			(keepout
				(tracks not_allowed)
				(vias allowed)
				(pads allowed)
				(copperpour not_allowed)
				(footprints allowed)
			)
			(placement
				(enabled no)
				(sheetname "")
			)
			(fill
				(thermal_gap 0.5)
				(thermal_bridge_width 0.5)
				(island_removal_mode 0)
			)
			(polygon
				(pts
					(xy 438.843928 -156.898848) (xy 438.843928 -157.406848) (xy 439.224928 -157.406848) (xy 439.224928 -156.898848)
				)
			)
		)
		(zone
			(layer "B.Cu")
			(hatch none 0.5)
			(connect_pads
				(clearance 0)
			)
			(min_thickness 0.25)
			(keepout
				(tracks allowed)
				(vias not_allowed)
				(pads allowed)
				(copperpour not_allowed)
				(footprints allowed)
			)
			(placement
				(enabled no)
				(sheetname "")
			)
			(fill
				(thermal_gap 0.5)
				(thermal_bridge_width 0.5)
				(island_removal_mode 0)
			)
			(polygon
				(pts
					(xy 439.224928 -156.898848) (xy 439.224928 -157.406848) (xy 438.843928 -157.406848) (xy 438.843928 -156.898848)
				)
			)
		)
	)
	(footprint ""
		(layer "B.Cu")
		(at 451.9422 -130.9624 180)
		(property "Reference" "R1M22"
			(at 0 0 0)
			(layer "B.SilkS")
			(hide yes)
			(effects
				(font
					(size 1.27 1.27)
				)
				(justify mirror)
			)
		)
		(property "Value" ""
			(at 0 0 0)
			(layer "B.Fab")
			(effects
				(font
					(size 1.27 1.27)
				)
				(justify mirror)
			)
		)
		(duplicate_pad_numbers_are_jumpers no)
		(fp_poly
			(pts
				(xy 0.2794 -0.1016) (xy -0.2794 -0.1016) (xy -0.2794 0.9906) (xy 0.2794 0.9906)
			)
			(stroke
				(width 0)
				(type default)
			)
			(fill no)
			(layer "B.CrtYd")
		)
		(fp_line
			(start 0.2794 0.9906)
			(end -0.2794 0.9906)
			(stroke
				(width 0.1)
				(type default)
			)
			(layer "B.Fab")
		)
		(fp_line
			(start 0.2794 -0.1016)
			(end 0.2794 0.9906)
			(stroke
				(width 0.1)
				(type default)
			)
			(layer "B.Fab")
		)
		(fp_line
			(start -0.2794 0.9906)
			(end -0.2794 -0.1016)
			(stroke
				(width 0.1)
				(type default)
			)
			(layer "B.Fab")
		)
		(fp_line
			(start -0.2794 -0.1016)
			(end 0.2794 -0.1016)
			(stroke
				(width 0.1)
				(type default)
			)
			(layer "B.Fab")
		)
		(pad "1" smd rect
			(at 0 0)
			(size 0.508 0.508)
			(layers "B.Cu" "B.Mask" "B.Paste")
			(net "JTAG_MCP_TMS_R1")
		)
		(pad "2" smd rect
			(at 0 0.889)
			(size 0.508 0.508)
			(layers "B.Cu" "B.Mask" "B.Paste")
			(net "JTAG_MCP_TMS")
		)
		(zone
			(layer "B.Cu")
			(hatch none 0.5)
			(connect_pads
				(clearance 0)
			)
			(min_thickness 0.25)
			(keepout
				(tracks not_allowed)
				(vias allowed)
				(pads allowed)
				(copperpour not_allowed)
				(footprints allowed)
			)
			(placement
				(enabled no)
				(sheetname "")
			)
			(fill
				(thermal_gap 0.5)
				(thermal_bridge_width 0.5)
				(island_removal_mode 0)
			)
			(polygon
				(pts
					(xy 451.6882 -131.5974) (xy 452.1962 -131.5974) (xy 452.1962 -131.2164) (xy 451.6882 -131.2164)
				)
			)
		)
		(zone
			(layer "B.Cu")
			(hatch none 0.5)
			(connect_pads
				(clearance 0)
			)
			(min_thickness 0.25)
			(keepout
				(tracks allowed)
				(vias not_allowed)
				(pads allowed)
				(copperpour not_allowed)
				(footprints allowed)
			)
			(placement
				(enabled no)
				(sheetname "")
			)
			(fill
				(thermal_gap 0.5)
				(thermal_bridge_width 0.5)
				(island_removal_mode 0)
			)
			(polygon
				(pts
					(xy 451.6882 -131.2164) (xy 452.1962 -131.2164) (xy 452.1962 -131.5974) (xy 451.6882 -131.5974)
				)
			)
		)
	)
)
